# BASEBOARD_FAB2 (Tioga Pass) — schematic netlist excerpt (pin names and nets, part order shuffled) for the footprints in the layout excerpt that follows; sources: Cadence DE-HDL packaged netlist, KiCad conversion of Wiwynn_Tioga_Pass_MB.brd

C3L17  CAP  10UF 16V 10% X6S  pkg 0805  page 219 : A = VR_FET_SW_P12V_STBY_PVDDQ_DEF ; B = GND
C2L50  CAP_A  0.01UF 25V 10% X7R  pkg 0402V  page 172 : A = SATA6G_S1_RX_C_DN ; B = SATA6G_S1_RX_DN
R780  RES  0.0 5% CHIP  pkg 0402  page 244 : A = P3E_CPU0_PE1_PCH_RXN<10> ; B = P3E_CPU0_PE1_PCH_CON_RXN<10>

(kicad_pcb
	(version 20260206)
	(generator "pcbnew")
	(generator_version "10.0")
	(general
		(thickness 1.6)
		(legacy_teardrops no)
	)
	(paper "A4")
	(title_block
		(title "Wiwynn_Tioga_Pass_MB.brd")
		(comment 1 "Tioga Pass / footprints 3913-3915 of 4770")
	)
	(layers
		(0 "F.Cu" signal "TOP")
		(4 "In1.Cu" signal "L2GND")
		(6 "In2.Cu" signal "L3")
		(8 "In3.Cu" signal "L4GND")
		(10 "In4.Cu" signal "L5")
		(12 "In5.Cu" signal "L6GND")
		(14 "In6.Cu" signal "L7VCC")
		(16 "In7.Cu" signal "L8VCC")
		(18 "In8.Cu" signal "L9GND")
		(20 "In9.Cu" signal "L10")
		(22 "In10.Cu" signal "L11GND")
		(24 "In11.Cu" signal "L12")
		(26 "In12.Cu" signal "L13GND")
		(2 "B.Cu" signal "BOTTOM")
		(9 "F.Adhes" user "F.Adhesive")
		(11 "B.Adhes" user "B.Adhesive")
		(13 "F.Paste" user "Package Geometry/Pastemask Top")
		(15 "B.Paste" user "Package Geometry/Pastemask Bottom")
		(5 "F.SilkS" user "Ref Des/Silkscreen Top")
		(7 "B.SilkS" user "Ref Des/Silkscreen Bottom")
		(1 "F.Mask" user "Board Geometry/Soldermask Top")
		(3 "B.Mask" user "Board Geometry/Soldermask Bottom")
		(17 "Dwgs.User" user "User.Drawings")
		(19 "Cmts.User" user "User.Comments")
		(21 "Eco1.User" user "User.Eco1")
		(23 "Eco2.User" user "User.Eco2")
		(25 "Edge.Cuts" user "Board Geometry/Outline")
		(27 "Margin" user)
		(31 "F.CrtYd" user "Package Geometry/Place Bound Top")
		(29 "B.CrtYd" user "Package Geometry/Place Bound Bottom")
		(35 "F.Fab" user "Ref Des/Assembly Top")
		(33 "B.Fab" user "Ref Des/Assembly Bottom")
	)
	(footprint ""
		(layer "B.Cu")
		(at 348.615 -144.565624 -90)
		(property "Reference" "C3L17"
			(at 0 0 90)
			(layer "B.SilkS")
			(hide yes)
			(effects
				(font
					(size 1.27 1.27)
				)
				(justify mirror)
			)
		)
		(property "Value" ""
			(at 0 0 90)
			(layer "B.Fab")
			(effects
				(font
					(size 1.27 1.27)
				)
				(justify mirror)
			)
		)
		(duplicate_pad_numbers_are_jumpers no)
		(fp_poly
			(pts
				(xy 0.7239 -0.2159) (xy -0.7239 -0.2159) (xy -0.7239 1.9939) (xy 0.7239 1.9939)
			)
			(stroke
				(width 0)
				(type default)
			)
			(fill no)
			(layer "B.CrtYd")
		)
		(fp_line
			(start -0.7239 1.9939)
			(end -0.7239 -0.2159)
			(stroke
				(width 0.1)
				(type default)
			)
			(layer "B.Fab")
		)
		(fp_line
			(start 0.7239 1.9939)
			(end -0.7239 1.9939)
			(stroke
				(width 0.1)
				(type default)
			)
			(layer "B.Fab")
		)
		(fp_line
			(start -0.7239 -0.2159)
			(end 0.7239 -0.2159)
			(stroke
				(width 0.1)
				(type default)
			)
			(layer "B.Fab")
		)
		(fp_line
			(start 0.7239 -0.2159)
			(end 0.7239 1.9939)
			(stroke
				(width 0.1)
				(type default)
			)
			(layer "B.Fab")
		)
		(pad "1" smd rect
			(at 0 0 90)
			(size 1.27 1.016)
			(layers "B.Cu" "B.Mask" "B.Paste")
			(net "VR_FET_SW_P12V_STBY_PVDDQ_DEF")
		)
		(pad "2" smd rect
			(at 0 1.778 90)
			(size 1.27 1.016)
			(layers "B.Cu" "B.Mask" "B.Paste")
			(net "GND")
		)
		(zone
			(layer "B.Cu")
			(hatch none 0.5)
			(connect_pads
				(clearance 0)
			)
			(min_thickness 0.25)
			(keepout
				(tracks not_allowed)
				(vias allowed)
				(pads allowed)
				(copperpour not_allowed)
				(footprints allowed)
			)
			(placement
				(enabled no)
				(sheetname "")
			)
			(fill
				(thermal_gap 0.5)
				(thermal_bridge_width 0.5)
				(island_removal_mode 0)
			)
			(polygon
				(pts
					(xy 348.107 -143.930624) (xy 348.107 -145.200624) (xy 347.345 -145.200624) (xy 347.345 -143.930624)
				)
			)
		)
	)
	(footprint ""
		(layer "B.Cu")
		(at 434.365654 -141.002512 180)
		(property "Reference" "C2L50"
			(at 0 0 0)
			(layer "B.SilkS")
			(hide yes)
			(effects
				(font
					(size 1.27 1.27)
				)
				(justify mirror)
			)
		)
		(property "Value" ""
			(at 0 0 0)
			(layer "B.Fab")
			(effects
				(font
					(size 1.27 1.27)
				)
				(justify mirror)
			)
		)
		(duplicate_pad_numbers_are_jumpers no)
		(fp_poly
			(pts
				(xy -0.3048 -0.1016) (xy -0.3048 0.9906) (xy 0.3048 0.9906) (xy 0.3048 -0.1016)
			)
			(stroke
				(width 0)
				(type default)
			)
			(fill no)
			(layer "B.CrtYd")
		)
		(fp_line
			(start 0.3048 0.9906)
			(end -0.3048 0.9906)
			(stroke
				(width 0.1)
				(type default)
			)
			(layer "B.Fab")
		)
		(fp_line
			(start 0.3048 -0.1016)
			(end 0.3048 0.9906)
			(stroke
				(width 0.1)
				(type default)
			)
			(layer "B.Fab")
		)
		(fp_line
			(start -0.3048 0.9906)
			(end -0.3048 -0.1016)
			(stroke
				(width 0.1)
				(type default)
			)
			(layer "B.Fab")
		)
		(fp_line
			(start -0.3048 -0.1016)
			(end 0.3048 -0.1016)
			(stroke
				(width 0.1)
				(type default)
			)
			(layer "B.Fab")
		)
		(pad "1" smd rect
			(at 0 0)
			(size 0.508 0.508)
			(layers "B.Cu" "B.Mask" "B.Paste")
			(net "SATA6G_S1_RX_C_DN")
		)
		(pad "2" smd rect
			(at 0 0.889)
			(size 0.508 0.508)
			(layers "B.Cu" "B.Mask" "B.Paste")
			(net "SATA6G_S1_RX_DN")
		)
		(zone
			(layer "B.Cu")
			(hatch none 0.5)
			(connect_pads
				(clearance 0)
			)
			(min_thickness 0.25)
			(keepout
				(tracks not_allowed)
				(vias allowed)
				(pads allowed)
				(copperpour not_allowed)
				(footprints allowed)
			)
			(placement
				(enabled no)
				(sheetname "")
			)
			(fill
				(thermal_gap 0.5)
				(thermal_bridge_width 0.5)
				(island_removal_mode 0)
			)
			(polygon
				(pts
					(xy 434.111654 -141.637512) (xy 434.619654 -141.637512) (xy 434.619654 -141.256512) (xy 434.111654 -141.256512)
				)
			)
		)
		(zone
			(layer "B.Cu")
			(hatch none 0.5)
			(connect_pads
				(clearance 0)
			)
			(min_thickness 0.25)
			(keepout
				(tracks allowed)
				(vias not_allowed)
				(pads allowed)
				(copperpour not_allowed)
				(footprints allowed)
			)
			(placement
				(enabled no)
				(sheetname "")
			)
			(fill
				(thermal_gap 0.5)
				(thermal_bridge_width 0.5)
				(island_removal_mode 0)
			)
			(polygon
				(pts
					(xy 434.111654 -141.256512) (xy 434.619654 -141.256512) (xy 434.619654 -141.637512) (xy 434.111654 -141.637512)
				)
			)
		)
	)
	(footprint ""
		(layer "B.Cu")
		(at 361.782614 -124.440442 -90)
		(property "Reference" "R780"
			(at 0.8382 -0.67818 270)
			(unlocked yes)
			(layer "B.SilkS")
			(effects
				(font
					(size 0.4064 0.254)
					(thickness 0.1524)
				)
				(justify left mirror)
			)
		)
		(property "Value" ""
			(at 0 0 90)
			(layer "B.Fab")
			(effects
				(font
					(size 1.27 1.27)
				)
				(justify mirror)
			)
		)
		(duplicate_pad_numbers_are_jumpers no)
		(fp_poly
			(pts
				(xy 0.2794 -0.1016) (xy -0.2794 -0.1016) (xy -0.2794 0.9906) (xy 0.2794 0.9906)
			)
			(stroke
				(width 0)
				(type default)
			)
			(fill no)
			(layer "B.CrtYd")
		)
		(fp_line
			(start -0.2794 0.9906)
			(end -0.2794 -0.1016)
			(stroke
				(width 0.1)
				(type default)
			)
			(layer "B.Fab")
		)
		(fp_line
			(start 0.2794 0.9906)
			(end -0.2794 0.9906)
			(stroke
				(width 0.1)
				(type default)
			)
			(layer "B.Fab")
		)
		(fp_line
			(start -0.2794 -0.1016)
			(end 0.2794 -0.1016)
			(stroke
				(width 0.1)
				(type default)
			)
			(layer "B.Fab")
		)
		(fp_line
			(start 0.2794 -0.1016)
			(end 0.2794 0.9906)
			(stroke
				(width 0.1)
				(type default)
			)
			(layer "B.Fab")
		)
		(pad "1" smd rect
			(at 0 0 90)
			(size 0.508 0.508)
			(layers "B.Cu" "B.Mask" "B.Paste")
			(net "P3E_CPU0_PE1_PCH_RXN<10>")
		)
		(pad "2" smd rect
			(at 0 0.889 90)
			(size 0.508 0.508)
			(layers "B.Cu" "B.Mask" "B.Paste")
			(net "P3E_CPU0_PE1_PCH_CON_RXN<10>")
		)
		(zone
			(layer "B.Cu")
			(hatch none 0.5)
			(connect_pads
				(clearance 0)
			)
			(min_thickness 0.25)
			(keepout
				(tracks not_allowed)
				(vias allowed)
				(pads allowed)
				(copperpour not_allowed)
				(footprints allowed)
			)
			(placement
				(enabled no)
				(sheetname "")
			)
			(fill
				(thermal_gap 0.5)
				(thermal_bridge_width 0.5)
				(island_removal_mode 0)
			)
			(polygon
				(pts
					(xy 361.147614 -124.186442) (xy 361.147614 -124.694442) (xy 361.528614 -124.694442) (xy 361.528614 -124.186442)
				)
			)
		)
		(zone
			(layer "B.Cu")
			(hatch none 0.5)
			(connect_pads
				(clearance 0)
			)
			(min_thickness 0.25)
			(keepout
				(tracks allowed)
				(vias not_allowed)
				(pads allowed)
				(copperpour not_allowed)
				(footprints allowed)
			)
			(placement
				(enabled no)
				(sheetname "")
			)
			(fill
				(thermal_gap 0.5)
				(thermal_bridge_width 0.5)
				(island_removal_mode 0)
			)
			(polygon
				(pts
					(xy 361.528614 -124.186442) (xy 361.528614 -124.694442) (xy 361.147614 -124.694442) (xy 361.147614 -124.186442)
				)
			)
		)
	)
)
